# S9S_MB_2U (Grand Teton) — schematic netlist excerpt (pin names and nets, part order shuffled) for the footprints in the layout excerpt that follows; sources: Cadence DE-HDL packaged netlist, KiCad conversion of 03242023_DA0F0TMBIJ0_F0T_Motherboard_J_brd_V01_OCP.brd

R4806  Q_RES  1K 1% CHIP  pkg 0402LF  page 306 : A = P12V_AUX ; B = U206_VDD
R3296  Q_RES  4.7K 1% CHIP  pkg 0402LF  page 190 : A = P3V3_AUX ; B = HDD_ACTIVITY_BUF

(kicad_pcb
	(version 20260206)
	(generator "pcbnew")
	(generator_version "10.0")
	(general
		(thickness 1.6)
		(legacy_teardrops no)
	)
	(paper "A4")
	(title_block
		(title "03242023_DA0F0TMBIJ0_F0T_Motherboard_J_brd_V01_OCP.brd")
		(comment 1 "Grand Teton / footprints 1154-1155 of 6105")
	)
	(layers
		(0 "F.Cu" signal "TOP")
		(4 "In1.Cu" signal "GND")
		(6 "In2.Cu" signal "IN1")
		(8 "In3.Cu" signal "GND1")
		(10 "In4.Cu" signal "IN2")
		(12 "In5.Cu" signal "GND2")
		(14 "In6.Cu" signal "IN3")
		(16 "In7.Cu" signal "GND3")
		(18 "In8.Cu" signal "VCC")
		(20 "In9.Cu" signal "VCC1")
		(22 "In10.Cu" signal "GND4")
		(24 "In11.Cu" signal "IN4")
		(26 "In12.Cu" signal "GND5")
		(28 "In13.Cu" signal "IN5")
		(30 "In14.Cu" signal "GND6")
		(32 "In15.Cu" signal "IN6")
		(34 "In16.Cu" signal "GND7")
		(2 "B.Cu" signal "BOTTOM")
		(9 "F.Adhes" user "F.Adhesive")
		(11 "B.Adhes" user "B.Adhesive")
		(13 "F.Paste" user "Package Geometry/Pastemask Top")
		(15 "B.Paste" user "Package Geometry/Pastemask Bottom")
		(5 "F.SilkS" user "Ref Des/Silkscreen Top")
		(7 "B.SilkS" user "Ref Des/Silkscreen Bottom")
		(1 "F.Mask" user "Board Geometry/Soldermask Top")
		(3 "B.Mask" user "Board Geometry/Soldermask Bottom")
		(17 "Dwgs.User" user "User.Drawings")
		(19 "Cmts.User" user "User.Comments")
		(21 "Eco1.User" user "User.Eco1")
		(23 "Eco2.User" user "User.Eco2")
		(25 "Edge.Cuts" user "Board Geometry/Outline")
		(27 "Margin" user)
		(31 "F.CrtYd" user "Package Geometry/Place Bound Top")
		(29 "B.CrtYd" user "Package Geometry/Place Bound Bottom")
		(35 "F.Fab" user "Ref Des/Assembly Top")
		(33 "B.Fab" user "Ref Des/Assembly Bottom")
	)
	(footprint ""
		(layer "F.Cu")
		(at 140.00988 -43.652948 180)
		(property "Reference" "R3296"
			(at 0 0 180)
			(layer "F.SilkS")
			(hide yes)
			(effects
				(font
					(size 1.27 1.27)
				)
			)
		)
		(property "Value" ""
			(at 0 0 180)
			(layer "F.Fab")
			(effects
				(font
					(size 1.27 1.27)
				)
			)
		)
		(duplicate_pad_numbers_are_jumpers no)
		(fp_line
			(start 0.7874 0.4064)
			(end -0.7874 0.4064)
			(stroke
				(width 0.1524)
				(type default)
			)
			(layer "F.SilkS")
		)
		(fp_line
			(start 0.7874 -0.4064)
			(end 0.7874 0.4064)
			(stroke
				(width 0.1524)
				(type default)
			)
			(layer "F.SilkS")
		)
		(fp_line
			(start -0.7874 0.4064)
			(end -0.7874 -0.4064)
			(stroke
				(width 0.1524)
				(type default)
			)
			(layer "F.SilkS")
		)
		(fp_line
			(start -0.7874 -0.4064)
			(end 0.7874 -0.4064)
			(stroke
				(width 0.1524)
				(type default)
			)
			(layer "F.SilkS")
		)
		(fp_line
			(start 0.67945 0.3048)
			(end 0.120396 0.3048)
			(stroke
				(width 0.1)
				(type default)
			)
			(layer "F.Fab")
		)
		(fp_line
			(start 0.67945 -0.3048)
			(end 0.67945 0.3048)
			(stroke
				(width 0.1)
				(type default)
			)
			(layer "F.Fab")
		)
		(fp_line
			(start 0.12065 -0.2794)
			(end 0.12065 -0.3048)
			(stroke
				(width 0.1)
				(type default)
			)
			(layer "F.Fab")
		)
		(fp_line
			(start 0.12065 -0.3048)
			(end 0.67945 -0.3048)
			(stroke
				(width 0.1)
				(type default)
			)
			(layer "F.Fab")
		)
		(fp_line
			(start 0.120396 0.3048)
			(end 0.120396 0.2794)
			(stroke
				(width 0.1)
				(type default)
			)
			(layer "F.Fab")
		)
		(fp_line
			(start 0.120396 0.2794)
			(end -0.12065 0.2794)
			(stroke
				(width 0.1)
				(type default)
			)
			(layer "F.Fab")
		)
		(fp_line
			(start -0.12065 0.3048)
			(end -0.67945 0.3048)
			(stroke
				(width 0.1)
				(type default)
			)
			(layer "F.Fab")
		)
		(fp_line
			(start -0.12065 0.2794)
			(end -0.12065 0.3048)
			(stroke
				(width 0.1)
				(type default)
			)
			(layer "F.Fab")
		)
		(fp_line
			(start -0.12065 -0.2794)
			(end 0.12065 -0.2794)
			(stroke
				(width 0.1)
				(type default)
			)
			(layer "F.Fab")
		)
		(fp_line
			(start -0.12065 -0.305054)
			(end -0.12065 -0.2794)
			(stroke
				(width 0.1)
				(type default)
			)
			(layer "F.Fab")
		)
		(fp_line
			(start -0.67945 0.3048)
			(end -0.67945 -0.305054)
			(stroke
				(width 0.1)
				(type default)
			)
			(layer "F.Fab")
		)
		(fp_line
			(start -0.67945 -0.305054)
			(end -0.12065 -0.305054)
			(stroke
				(width 0.1)
				(type default)
			)
			(layer "F.Fab")
		)
		(pad "1" smd circle
			(at -0.40005 0 180)
			(size 0 0)
			(layers "F.Cu" "F.Mask" "F.Paste")
			(net "P3V3_AUX")
		)
		(pad "2" smd circle
			(at 0.40005 0 180)
			(size 0 0)
			(layers "F.Cu" "F.Mask" "F.Paste")
			(net "HDD_ACTIVITY_BUF")
		)
	)
	(footprint ""
		(layer "F.Cu")
		(at 220.087444 -101.24948 180)
		(property "Reference" "R4806"
			(at 0 0 180)
			(layer "F.SilkS")
			(hide yes)
			(effects
				(font
					(size 1.27 1.27)
				)
			)
		)
		(property "Value" ""
			(at 0 0 180)
			(layer "F.Fab")
			(effects
				(font
					(size 1.27 1.27)
				)
			)
		)
		(duplicate_pad_numbers_are_jumpers no)
		(fp_line
			(start 0.7874 0.4064)
			(end -0.7874 0.4064)
			(stroke
				(width 0.1524)
				(type default)
			)
			(layer "F.SilkS")
		)
		(fp_line
			(start 0.7874 -0.4064)
			(end 0.7874 0.4064)
			(stroke
				(width 0.1524)
				(type default)
			)
			(layer "F.SilkS")
		)
		(fp_line
			(start -0.7874 0.4064)
			(end -0.7874 -0.4064)
			(stroke
				(width 0.1524)
				(type default)
			)
			(layer "F.SilkS")
		)
		(fp_line
			(start -0.7874 -0.4064)
			(end 0.7874 -0.4064)
			(stroke
				(width 0.1524)
				(type default)
			)
			(layer "F.SilkS")
		)
		(fp_line
			(start 0.67945 0.3048)
			(end 0.120396 0.3048)
			(stroke
				(width 0.1)
				(type default)
			)
			(layer "F.Fab")
		)
		(fp_line
			(start 0.67945 -0.3048)
			(end 0.67945 0.3048)
			(stroke
				(width 0.1)
				(type default)
			)
			(layer "F.Fab")
		)
		(fp_line
			(start 0.12065 -0.2794)
			(end 0.12065 -0.3048)
			(stroke
				(width 0.1)
				(type default)
			)
			(layer "F.Fab")
		)
		(fp_line
			(start 0.12065 -0.3048)
			(end 0.67945 -0.3048)
			(stroke
				(width 0.1)
				(type default)
			)
			(layer "F.Fab")
		)
		(fp_line
			(start 0.120396 0.3048)
			(end 0.120396 0.2794)
			(stroke
				(width 0.1)
				(type default)
			)
			(layer "F.Fab")
		)
		(fp_line
			(start 0.120396 0.2794)
			(end -0.12065 0.2794)
			(stroke
				(width 0.1)
				(type default)
			)
			(layer "F.Fab")
		)
		(fp_line
			(start -0.12065 0.3048)
			(end -0.67945 0.3048)
			(stroke
				(width 0.1)
				(type default)
			)
			(layer "F.Fab")
		)
		(fp_line
			(start -0.12065 0.2794)
			(end -0.12065 0.3048)
			(stroke
				(width 0.1)
				(type default)
			)
			(layer "F.Fab")
		)
		(fp_line
			(start -0.12065 -0.2794)
			(end 0.12065 -0.2794)
			(stroke
				(width 0.1)
				(type default)
			)
			(layer "F.Fab")
		)
		(fp_line
			(start -0.12065 -0.305054)
			(end -0.12065 -0.2794)
			(stroke
				(width 0.1)
				(type default)
			)
			(layer "F.Fab")
		)
		(fp_line
			(start -0.67945 0.3048)
			(end -0.67945 -0.305054)
			(stroke
				(width 0.1)
				(type default)
			)
			(layer "F.Fab")
		)
		(fp_line
			(start -0.67945 -0.305054)
			(end -0.12065 -0.305054)
			(stroke
				(width 0.1)
				(type default)
			)
			(layer "F.Fab")
		)
		(pad "1" smd circle
			(at -0.40005 0 180)
			(size 0 0)
			(layers "F.Cu" "F.Mask" "F.Paste")
			(net "P12V_AUX")
		)
		(pad "2" smd circle
			(at 0.40005 0 180)
			(size 0 0)
			(layers "F.Cu" "F.Mask" "F.Paste")
			(net "U206_VDD")
		)
	)
)
